# S9S_MB_2U (Grand Teton) — schematic netlist excerpt (pin names and nets, part order shuffled) for the footprints in the layout excerpt that follows; sources: Cadence DE-HDL packaged netlist, KiCad conversion of 03242023_DA0F0TMBIJ0_F0T_Motherboard_J_brd_V01_OCP.brd

R3506  Q_RES  4.7K 5% EMPTY  pkg 0402LF  page 151 : A = P3V3_AUX ; B = GPU_FPGA_RST_R_N
R4762  Q_RES  10K 1% CHIP  pkg 0402LF  page 156 : A = P3V3_AUX ; B = HP_LVC3_OCP_V3_1_PRSNT2_PLD_N
C705  Q_CAP_DIFFBUS  DIFF BUS_0.22UF 6.3V 20% X6S  pkg C0201  page 177 : \1\ = P5E_CPU1_PE4_TX_C_DP<2> ; \2\ = P5E_CPU1_PE4_TX_DP<2>

(kicad_pcb
	(version 20260206)
	(generator "pcbnew")
	(generator_version "10.0")
	(general
		(thickness 1.6)
		(legacy_teardrops no)
	)
	(paper "A4")
	(title_block
		(title "03242023_DA0F0TMBIJ0_F0T_Motherboard_J_brd_V01_OCP.brd")
		(comment 1 "Grand Teton / footprints 954-956 of 6105")
	)
	(layers
		(0 "F.Cu" signal "TOP")
		(4 "In1.Cu" signal "GND")
		(6 "In2.Cu" signal "IN1")
		(8 "In3.Cu" signal "GND1")
		(10 "In4.Cu" signal "IN2")
		(12 "In5.Cu" signal "GND2")
		(14 "In6.Cu" signal "IN3")
		(16 "In7.Cu" signal "GND3")
		(18 "In8.Cu" signal "VCC")
		(20 "In9.Cu" signal "VCC1")
		(22 "In10.Cu" signal "GND4")
		(24 "In11.Cu" signal "IN4")
		(26 "In12.Cu" signal "GND5")
		(28 "In13.Cu" signal "IN5")
		(30 "In14.Cu" signal "GND6")
		(32 "In15.Cu" signal "IN6")
		(34 "In16.Cu" signal "GND7")
		(2 "B.Cu" signal "BOTTOM")
		(9 "F.Adhes" user "F.Adhesive")
		(11 "B.Adhes" user "B.Adhesive")
		(13 "F.Paste" user "Package Geometry/Pastemask Top")
		(15 "B.Paste" user "Package Geometry/Pastemask Bottom")
		(5 "F.SilkS" user "Ref Des/Silkscreen Top")
		(7 "B.SilkS" user "Ref Des/Silkscreen Bottom")
		(1 "F.Mask" user "Board Geometry/Soldermask Top")
		(3 "B.Mask" user "Board Geometry/Soldermask Bottom")
		(17 "Dwgs.User" user "User.Drawings")
		(19 "Cmts.User" user "User.Comments")
		(21 "Eco1.User" user "User.Eco1")
		(23 "Eco2.User" user "User.Eco2")
		(25 "Edge.Cuts" user "Board Geometry/Outline")
		(27 "Margin" user)
		(31 "F.CrtYd" user "Package Geometry/Place Bound Top")
		(29 "B.CrtYd" user "Package Geometry/Place Bound Bottom")
		(35 "F.Fab" user "Ref Des/Assembly Top")
		(33 "B.Fab" user "Ref Des/Assembly Bottom")
	)
	(footprint ""
		(layer "F.Cu")
		(at 461.593946 -105.011728 180)
		(property "Reference" "R4762"
			(at 0 0 180)
			(layer "F.SilkS")
			(hide yes)
			(effects
				(font
					(size 1.27 1.27)
				)
			)
		)
		(property "Value" ""
			(at 0 0 180)
			(layer "F.Fab")
			(effects
				(font
					(size 1.27 1.27)
				)
			)
		)
		(duplicate_pad_numbers_are_jumpers no)
		(fp_line
			(start 0.7874 0.4064)
			(end -0.7874 0.4064)
			(stroke
				(width 0.1524)
				(type default)
			)
			(layer "F.SilkS")
		)
		(fp_line
			(start 0.7874 -0.4064)
			(end 0.7874 0.4064)
			(stroke
				(width 0.1524)
				(type default)
			)
			(layer "F.SilkS")
		)
		(fp_line
			(start -0.7874 0.4064)
			(end -0.7874 -0.4064)
			(stroke
				(width 0.1524)
				(type default)
			)
			(layer "F.SilkS")
		)
		(fp_line
			(start -0.7874 -0.4064)
			(end 0.7874 -0.4064)
			(stroke
				(width 0.1524)
				(type default)
			)
			(layer "F.SilkS")
		)
		(fp_line
			(start 0.67945 0.3048)
			(end 0.120396 0.3048)
			(stroke
				(width 0.1)
				(type default)
			)
			(layer "F.Fab")
		)
		(fp_line
			(start 0.67945 -0.3048)
			(end 0.67945 0.3048)
			(stroke
				(width 0.1)
				(type default)
			)
			(layer "F.Fab")
		)
		(fp_line
			(start 0.12065 -0.2794)
			(end 0.12065 -0.3048)
			(stroke
				(width 0.1)
				(type default)
			)
			(layer "F.Fab")
		)
		(fp_line
			(start 0.12065 -0.3048)
			(end 0.67945 -0.3048)
			(stroke
				(width 0.1)
				(type default)
			)
			(layer "F.Fab")
		)
		(fp_line
			(start 0.120396 0.3048)
			(end 0.120396 0.2794)
			(stroke
				(width 0.1)
				(type default)
			)
			(layer "F.Fab")
		)
		(fp_line
			(start 0.120396 0.2794)
			(end -0.12065 0.2794)
			(stroke
				(width 0.1)
				(type default)
			)
			(layer "F.Fab")
		)
		(fp_line
			(start -0.12065 0.3048)
			(end -0.67945 0.3048)
			(stroke
				(width 0.1)
				(type default)
			)
			(layer "F.Fab")
		)
		(fp_line
			(start -0.12065 0.2794)
			(end -0.12065 0.3048)
			(stroke
				(width 0.1)
				(type default)
			)
			(layer "F.Fab")
		)
		(fp_line
			(start -0.12065 -0.2794)
			(end 0.12065 -0.2794)
			(stroke
				(width 0.1)
				(type default)
			)
			(layer "F.Fab")
		)
		(fp_line
			(start -0.12065 -0.305054)
			(end -0.12065 -0.2794)
			(stroke
				(width 0.1)
				(type default)
			)
			(layer "F.Fab")
		)
		(fp_line
			(start -0.67945 0.3048)
			(end -0.67945 -0.305054)
			(stroke
				(width 0.1)
				(type default)
			)
			(layer "F.Fab")
		)
		(fp_line
			(start -0.67945 -0.305054)
			(end -0.12065 -0.305054)
			(stroke
				(width 0.1)
				(type default)
			)
			(layer "F.Fab")
		)
		(pad "1" smd circle
			(at -0.40005 0 180)
			(size 0 0)
			(layers "F.Cu" "F.Mask" "F.Paste")
			(net "P3V3_AUX")
		)
		(pad "2" smd circle
			(at 0.40005 0 180)
			(size 0 0)
			(layers "F.Cu" "F.Mask" "F.Paste")
			(net "HP_LVC3_OCP_V3_1_PRSNT2_PLD_N")
		)
	)
	(footprint ""
		(layer "F.Cu")
		(at 56.341518 -408.517344 -90)
		(property "Reference" "C705"
			(at 0 0 270)
			(layer "F.SilkS")
			(hide yes)
			(effects
				(font
					(size 1.27 1.27)
				)
			)
		)
		(property "Value" ""
			(at 0 0 270)
			(layer "F.Fab")
			(effects
				(font
					(size 1.27 1.27)
				)
			)
		)
		(duplicate_pad_numbers_are_jumpers no)
		(fp_line
			(start -0.299974 0.150114)
			(end -0.299974 -0.150114)
			(stroke
				(width 0.1)
				(type default)
			)
			(layer "F.Fab")
		)
		(fp_line
			(start 0.299974 0.150114)
			(end -0.299974 0.150114)
			(stroke
				(width 0.1)
				(type default)
			)
			(layer "F.Fab")
		)
		(fp_line
			(start -0.299974 -0.150114)
			(end 0.299974 -0.150114)
			(stroke
				(width 0.1)
				(type default)
			)
			(layer "F.Fab")
		)
		(fp_line
			(start 0.299974 -0.150114)
			(end 0.299974 0.150114)
			(stroke
				(width 0.1)
				(type default)
			)
			(layer "F.Fab")
		)
		(pad "1" smd rect
			(at -0.2667 0 270)
			(size 0.3048 0.381)
			(layers "F.Cu" "F.Mask" "F.Paste")
			(net "P5E_CPU1_PE4_TX_C_DP<2>")
		)
		(pad "2" smd rect
			(at 0.2667 0 270)
			(size 0.3048 0.381)
			(layers "F.Cu" "F.Mask" "F.Paste")
			(net "P5E_CPU1_PE4_TX_DP<2>")
		)
	)
	(footprint ""
		(layer "F.Cu")
		(at 120.36044 -427.091348 180)
		(property "Reference" "R3506"
			(at 0 0 180)
			(layer "F.SilkS")
			(hide yes)
			(effects
				(font
					(size 1.27 1.27)
				)
			)
		)
		(property "Value" ""
			(at 0 0 180)
			(layer "F.Fab")
			(effects
				(font
					(size 1.27 1.27)
				)
			)
		)
		(duplicate_pad_numbers_are_jumpers no)
		(fp_line
			(start 0.7874 0.4064)
			(end -0.7874 0.4064)
			(stroke
				(width 0.1524)
				(type default)
			)
			(layer "F.SilkS")
		)
		(fp_line
			(start 0.7874 -0.4064)
			(end 0.7874 0.4064)
			(stroke
				(width 0.1524)
				(type default)
			)
			(layer "F.SilkS")
		)
		(fp_line
			(start -0.7874 0.4064)
			(end -0.7874 -0.4064)
			(stroke
				(width 0.1524)
				(type default)
			)
			(layer "F.SilkS")
		)
		(fp_line
			(start -0.7874 -0.4064)
			(end 0.7874 -0.4064)
			(stroke
				(width 0.1524)
				(type default)
			)
			(layer "F.SilkS")
		)
		(fp_line
			(start 0.67945 0.3048)
			(end 0.120396 0.3048)
			(stroke
				(width 0.1)
				(type default)
			)
			(layer "F.Fab")
		)
		(fp_line
			(start 0.67945 -0.3048)
			(end 0.67945 0.3048)
			(stroke
				(width 0.1)
				(type default)
			)
			(layer "F.Fab")
		)
		(fp_line
			(start 0.12065 -0.2794)
			(end 0.12065 -0.3048)
			(stroke
				(width 0.1)
				(type default)
			)
			(layer "F.Fab")
		)
		(fp_line
			(start 0.12065 -0.3048)
			(end 0.67945 -0.3048)
			(stroke
				(width 0.1)
				(type default)
			)
			(layer "F.Fab")
		)
		(fp_line
			(start 0.120396 0.3048)
			(end 0.120396 0.2794)
			(stroke
				(width 0.1)
				(type default)
			)
			(layer "F.Fab")
		)
		(fp_line
			(start 0.120396 0.2794)
			(end -0.12065 0.2794)
			(stroke
				(width 0.1)
				(type default)
			)
			(layer "F.Fab")
		)
		(fp_line
			(start -0.12065 0.3048)
			(end -0.67945 0.3048)
			(stroke
				(width 0.1)
				(type default)
			)
			(layer "F.Fab")
		)
		(fp_line
			(start -0.12065 0.2794)
			(end -0.12065 0.3048)
			(stroke
				(width 0.1)
				(type default)
			)
			(layer "F.Fab")
		)
		(fp_line
			(start -0.12065 -0.2794)
			(end 0.12065 -0.2794)
			(stroke
				(width 0.1)
				(type default)
			)
			(layer "F.Fab")
		)
		(fp_line
			(start -0.12065 -0.305054)
			(end -0.12065 -0.2794)
			(stroke
				(width 0.1)
				(type default)
			)
			(layer "F.Fab")
		)
		(fp_line
			(start -0.67945 0.3048)
			(end -0.67945 -0.305054)
			(stroke
				(width 0.1)
				(type default)
			)
			(layer "F.Fab")
		)
		(fp_line
			(start -0.67945 -0.305054)
			(end -0.12065 -0.305054)
			(stroke
				(width 0.1)
				(type default)
			)
			(layer "F.Fab")
		)
		(pad "1" smd circle
			(at -0.40005 0 180)
			(size 0 0)
			(layers "F.Cu" "F.Mask" "F.Paste")
			(net "P3V3_AUX")
		)
		(pad "2" smd circle
			(at 0.40005 0 180)
			(size 0 0)
			(layers "F.Cu" "F.Mask" "F.Paste")
			(net "GPU_FPGA_RST_R_N")
		)
	)
)
